(kicad_pcb
	(version 20240108)
	(generator "pcbnew")
	(generator_version "8.0")
	(general
		(thickness 1.62)
		(legacy_teardrops no)
	)
	(paper "A4")
	(title_block
		(title "Jetson Orin Baseboard")
		(date "2025-03-12")
		(rev "1.3.4")
		(company "Antmicro Ltd")
		(comment 1 "www.antmicro.com")
		(comment 9 "footprints 165-169 of 677")
	)
	(layers
		(0 "F.Cu" signal)
		(1 "In1.Cu" signal)
		(2 "In2.Cu" signal)
		(3 "In3.Cu" signal)
		(4 "In4.Cu" jumper)
		(5 "In5.Cu" signal)
		(6 "In6.Cu" signal)
		(31 "B.Cu" signal)
		(32 "B.Adhes" user "B.Adhesive")
		(33 "F.Adhes" user "F.Adhesive")
		(34 "B.Paste" user)
		(35 "F.Paste" user)
		(36 "B.SilkS" user "B.Silkscreen")
		(37 "F.SilkS" user "F.Silkscreen")
		(38 "B.Mask" user)
		(39 "F.Mask" user)
		(40 "Dwgs.User" user "User.Drawings")
		(41 "Cmts.User" user "User.Comments")
		(42 "Eco1.User" user "User.Eco1")
		(43 "Eco2.User" user "User.Eco2")
		(44 "Edge.Cuts" user)
		(45 "Margin" user)
		(46 "B.CrtYd" user "B.Courtyard")
		(47 "F.CrtYd" user "F.Courtyard")
		(48 "B.Fab" user)
		(49 "F.Fab" user)
	)
	(footprint "antmicro-footprints:R_0603_1608Metric"
		(layer "F.Cu")
		(at 137.2 115.9 180)
		(descr "Resistor SMD 0603")
		(tags "resistor SMD 0603")
		(property "Reference" "R247"
			(at 4.05 -0.4 180)
			(layer "F.SilkS")
			(effects
				(font
					(size 0.7 0.7)
					(thickness 0.15)
				)
				(justify left bottom)
			)
		)
		(property "Value" "R_0R_0603"
			(at 0 1.6 180)
			(layer "F.Fab")
			(effects
				(font
					(size 0.7 0.7)
					(thickness 0.15)
				)
				(justify left bottom)
			)
		)
		(property "Footprint" "antmicro-footprints:R_0603_1608Metric"
			(at 0 0 180)
			(layer "F.Fab")
			(hide yes)
			(effects
				(font
					(size 1.27 1.27)
					(thickness 0.15)
				)
			)
		)
		(property "Datasheet" "https://www.bourns.com/docs/product-datasheets/cr.pdf?sfvrsn=574d41f6_14"
			(at 0 0 180)
			(layer "F.Fab")
			(hide yes)
			(effects
				(font
					(size 1.27 1.27)
					(thickness 0.15)
				)
			)
		)
		(property "Author" "Antmicro"
			(at 274.4 231.8 0)
			(layer "F.Fab")
			(hide yes)
			(effects
				(font
					(size 1 1)
					(thickness 0.15)
				)
			)
		)
		(property "Current" "1A"
			(at 274.4 231.8 0)
			(layer "F.Fab")
			(hide yes)
			(effects
				(font
					(size 1 1)
					(thickness 0.15)
				)
			)
		)
		(property "License" "Apache-2.0"
			(at 274.4 231.8 0)
			(layer "F.Fab")
			(hide yes)
			(effects
				(font
					(size 1 1)
					(thickness 0.15)
				)
			)
		)
		(property "MPN" "CR0603-J/-000ELF"
			(at 274.4 231.8 0)
			(layer "F.Fab")
			(hide yes)
			(effects
				(font
					(size 1 1)
					(thickness 0.15)
				)
			)
		)
		(property "Manufacturer" "Bourns"
			(at 274.4 231.8 0)
			(layer "F.Fab")
			(hide yes)
			(effects
				(font
					(size 1 1)
					(thickness 0.15)
				)
			)
		)
		(property "Tolerance" ""
			(at 274.4 231.8 0)
			(layer "F.Fab")
			(hide yes)
			(effects
				(font
					(size 1 1)
					(thickness 0.15)
				)
			)
		)
		(property "Val" "0R"
			(at 274.4 231.8 0)
			(layer "F.Fab")
			(hide yes)
			(effects
				(font
					(size 1 1)
					(thickness 0.15)
				)
			)
		)
		(sheetname "Peripherals")
		(sheetfile "peripherals.kicad_sch")
		(attr smd)
		(fp_line
			(start -0.15 0.4)
			(end 0.15 0.4)
			(stroke
				(width 0.15)
				(type solid)
			)
			(layer "F.SilkS")
		)
		(fp_line
			(start -0.15 -0.4)
			(end 0.15 -0.4)
			(stroke
				(width 0.15)
				(type solid)
			)
			(layer "F.SilkS")
		)
		(fp_rect
			(start -1.25 -0.65)
			(end 1.25 0.65)
			(stroke
				(width 0.05)
				(type solid)
			)
			(fill none)
			(layer "F.CrtYd")
		)
		(fp_rect
			(start -0.8 -0.4)
			(end 0.8 0.4)
			(stroke
				(width 0.15)
				(type solid)
			)
			(fill none)
			(layer "F.Fab")
		)
		(fp_text user "Author: Antmicro"
			(at -1.25 4.9 180)
			(layer "F.Fab")
			(hide yes)
			(effects
				(font
					(size 0.7 0.7)
					(thickness 0.15)
				)
				(justify left bottom)
			)
		)
		(fp_text user "License: Apache-2.0"
			(at -1.25 5.9 180)
			(layer "F.Fab")
			(hide yes)
			(effects
				(font
					(size 0.7 0.7)
					(thickness 0.15)
				)
				(justify left bottom)
			)
		)
		(fp_text user "${REFERENCE}"
			(at -1.25 3.898 180)
			(layer "F.Fab")
			(hide yes)
			(effects
				(font
					(size 0.7 0.7)
					(thickness 0.15)
				)
				(justify left bottom)
			)
		)
		(pad "1" smd roundrect
			(at -0.7 0 180)
			(size 0.8 1)
			(layers "F.Cu" "F.Paste" "F.Mask")
			(roundrect_rratio 0.2)
			(net 484 "/Peripherals/3V3_STDB_CONN")
			(pintype "passive")
		)
		(pad "2" smd roundrect
			(at 0.7 0 180)
			(size 0.8 1)
			(layers "F.Cu" "F.Paste" "F.Mask")
			(roundrect_rratio 0.2)
			(net 117 "3V3_STDB")
			(pintype "passive")
		)
	)
	(footprint "antmicro-footprints:R_0402_1005Metric"
		(layer "F.Cu")
		(at 69.69 82.31 -90)
		(descr "Resistor SMD 0402")
		(tags "resistor SMD 0402")
		(property "Reference" "R4"
			(at 0.84 0.33 90)
			(layer "F.SilkS")
			(effects
				(font
					(size 0.7 0.7)
					(thickness 0.15)
				)
				(justify right top)
			)
		)
		(property "Value" "R_0R_0402"
			(at 0 1.4 90)
			(layer "F.Fab")
			(effects
				(font
					(size 0.7 0.7)
					(thickness 0.15)
				)
				(justify right top)
			)
		)
		(property "Footprint" "antmicro-footprints:R_0402_1005Metric"
			(at 0 0 90)
			(layer "F.Fab")
			(hide yes)
			(effects
				(font
					(size 1.27 1.27)
					(thickness 0.15)
				)
			)
		)
		(property "Datasheet" "https://industrial.panasonic.com/cdbs/www-data/pdf/RDA0000/AOA0000C301.pdf"
			(at 0 0 90)
			(layer "F.Fab")
			(hide yes)
			(effects
				(font
					(size 1.27 1.27)
					(thickness 0.15)
				)
			)
		)
		(property "Author" "Antmicro"
			(at -13.14905 151.95095 0)
			(layer "F.Fab")
			(hide yes)
			(effects
				(font
					(size 1 1)
					(thickness 0.15)
				)
			)
		)
		(property "Current" "1A"
			(at -13.14905 151.95095 0)
			(layer "F.Fab")
			(hide yes)
			(effects
				(font
					(size 1 1)
					(thickness 0.15)
				)
			)
		)
		(property "License" "Apache-2.0"
			(at -13.14905 151.95095 0)
			(layer "F.Fab")
			(hide yes)
			(effects
				(font
					(size 1 1)
					(thickness 0.15)
				)
			)
		)
		(property "MPN" "ERJ2GE0R00X"
			(at -13.14905 151.95095 0)
			(layer "F.Fab")
			(hide yes)
			(effects
				(font
					(size 1 1)
					(thickness 0.15)
				)
			)
		)
		(property "Manufacturer" "Panasonic"
			(at -13.14905 151.95095 0)
			(layer "F.Fab")
			(hide yes)
			(effects
				(font
					(size 1 1)
					(thickness 0.15)
				)
			)
		)
		(property "Tolerance" ""
			(at -13.14905 151.95095 0)
			(layer "F.Fab")
			(hide yes)
			(effects
				(font
					(size 1 1)
					(thickness 0.15)
				)
			)
		)
		(property "Val" "0R"
			(at -13.14905 151.95095 0)
			(layer "F.Fab")
			(hide yes)
			(effects
				(font
					(size 1 1)
					(thickness 0.15)
				)
			)
		)
		(sheetname "SoM")
		(sheetfile "som.kicad_sch")
		(attr smd exclude_from_pos_files exclude_from_bom dnp)
		(fp_rect
			(start -0.925 -0.47)
			(end 0.925 0.47)
			(stroke
				(width 0.05)
				(type default)
			)
			(fill none)
			(layer "F.CrtYd")
		)
		(fp_rect
			(start -0.5 -0.25)
			(end 0.5 0.25)
			(stroke
				(width 0.15)
				(type solid)
			)
			(fill none)
			(layer "F.Fab")
		)
		(fp_text user "${REFERENCE}"
			(at -0.95 3.168 90)
			(layer "F.Fab")
			(hide yes)
			(effects
				(font
					(size 0.7 0.7)
					(thickness 0.15)
				)
				(justify right top)
			)
		)
		(fp_text user "Author: Antmicro"
			(at -0.95 4.169 90)
			(layer "F.Fab")
			(hide yes)
			(effects
				(font
					(size 0.7 0.7)
					(thickness 0.15)
				)
				(justify right top)
			)
		)
		(fp_text user "License: Apache-2.0"
			(at -0.95 5.169 90)
			(layer "F.Fab")
			(hide yes)
			(effects
				(font
					(size 0.7 0.7)
					(thickness 0.15)
				)
				(justify right top)
			)
		)
		(pad "1" smd roundrect
			(at -0.48 0 270)
			(size 0.59 0.64)
			(layers "F.Cu" "F.Paste" "F.Mask")
			(roundrect_rratio 0.25)
			(net 752 "Net-(J15H-GPIO12{slash}PWM)")
			(pintype "passive")
		)
		(pad "2" smd roundrect
			(at 0.48 0 270)
			(size 0.59 0.64)
			(layers "F.Cu" "F.Paste" "F.Mask")
			(roundrect_rratio 0.25)
			(net 242 "VSYNC_CAM2")
			(pintype "passive")
		)
	)
	(footprint "antmicro-footprints:C_0805_2012Metric"
		(layer "F.Cu")
		(at 71.58 86.82)
		(descr "Capacitor SMD 0805")
		(tags "capacitor SMD 0805")
		(property "Reference" "C122"
			(at -1.4 -0.91 0)
			(layer "F.SilkS")
			(effects
				(font
					(size 0.7 0.7)
					(thickness 0.15)
				)
				(justify left bottom)
			)
		)
		(property "Value" "C_22u_25V_0805"
			(at -2.055717 1.963152 0)
			(layer "F.Fab")
			(effects
				(font
					(size 0.7 0.7)
					(thickness 0.15)
				)
				(justify left bottom)
			)
		)
		(property "Footprint" "antmicro-footprints:C_0805_2012Metric"
			(at 0 0 0)
			(layer "F.Fab")
			(hide yes)
			(effects
				(font
					(size 1.27 1.27)
					(thickness 0.15)
				)
			)
		)
		(property "Datasheet" "https://product.samsungsem.com/mlcc/CL21A226MAYNNN.do"
			(at 0 0 0)
			(layer "F.Fab")
			(hide yes)
			(effects
				(font
					(size 1.27 1.27)
					(thickness 0.15)
				)
			)
		)
		(property "Author" "Antmicro"
			(at 0 0 0)
			(layer "F.Fab")
			(hide yes)
			(effects
				(font
					(size 1 1)
					(thickness 0.15)
				)
			)
		)
		(property "Dielectric" "X5R"
			(at 0 0 0)
			(layer "F.Fab")
			(hide yes)
			(effects
				(font
					(size 1 1)
					(thickness 0.15)
				)
			)
		)
		(property "License" "Apache-2.0"
			(at 0 0 0)
			(layer "F.Fab")
			(hide yes)
			(effects
				(font
					(size 1 1)
					(thickness 0.15)
				)
			)
		)
		(property "MPN" "CL21A226MAYNNNE"
			(at 0 0 0)
			(layer "F.Fab")
			(hide yes)
			(effects
				(font
					(size 1 1)
					(thickness 0.15)
				)
			)
		)
		(property "Manufacturer" "Samsung Electro-Mechanics"
			(at 0 0 0)
			(layer "F.Fab")
			(hide yes)
			(effects
				(font
					(size 1 1)
					(thickness 0.15)
				)
			)
		)
		(property "Public" "False"
			(at 0 0 0)
			(layer "F.Fab")
			(hide yes)
			(effects
				(font
					(size 1 1)
					(thickness 0.15)
				)
			)
		)
		(property "Val" "22u"
			(at 0 0 0)
			(layer "F.Fab")
			(hide yes)
			(effects
				(font
					(size 1 1)
					(thickness 0.15)
				)
			)
		)
		(property "Voltage" "25V"
			(at 0 0 0)
			(layer "F.Fab")
			(hide yes)
			(effects
				(font
					(size 1 1)
					(thickness 0.15)
				)
			)
		)
		(sheetname "Supply")
		(sheetfile "supply.kicad_sch")
		(attr smd)
		(fp_line
			(start -0.3 -0.7)
			(end 0.3 -0.7)
			(stroke
				(width 0.15)
				(type solid)
			)
			(layer "F.SilkS")
		)
		(fp_line
			(start -0.3 0.7)
			(end 0.3 0.7)
			(stroke
				(width 0.15)
				(type solid)
			)
			(layer "F.SilkS")
		)
		(fp_rect
			(start 1.95 -0.9)
			(end -1.95 0.9)
			(stroke
				(width 0.05)
				(type default)
			)
			(fill none)
			(layer "F.CrtYd")
		)
		(fp_rect
			(start -0.95 -0.675)
			(end 0.95 0.675)
			(stroke
				(width 0.15)
				(type solid)
			)
			(fill none)
			(layer "F.Fab")
		)
		(fp_text user "License: Apache-2.0"
			(at -1.9 4.947 0)
			(layer "F.Fab")
			(hide yes)
			(effects
				(font
					(size 0.7 0.7)
					(thickness 0.15)
				)
				(justify left bottom)
			)
		)
		(fp_text user "${REFERENCE}"
			(at -1.9 3.947 0)
			(layer "F.Fab")
			(hide yes)
			(effects
				(font
					(size 0.7 0.7)
					(thickness 0.15)
				)
				(justify left bottom)
			)
		)
		(fp_text user "Author: Antmicro"
			(at -1.9 5.947 0)
			(layer "F.Fab")
			(hide yes)
			(effects
				(font
					(size 0.7 0.7)
					(thickness 0.15)
				)
				(justify left bottom)
			)
		)
		(pad "1" smd roundrect
			(at -1.1 0)
			(size 1.2 1.3)
			(layers "F.Cu" "F.Paste" "F.Mask")
			(roundrect_rratio 0.25)
			(net 1 "GND")
			(pintype "passive")
		)
		(pad "2" smd roundrect
			(at 1.1 0)
			(size 1.2 1.3)
			(layers "F.Cu" "F.Paste" "F.Mask")
			(roundrect_rratio 0.25)
			(net 115 "VCC")
			(pintype "passive")
		)
	)
	(footprint "antmicro-footprints:R_0402_1005Metric"
		(layer "F.Cu")
		(at 148 110.5 180)
		(descr "Resistor SMD 0402")
		(tags "resistor SMD 0402")
		(property "Reference" "R335"
			(at 1.21 -5.91 180)
			(layer "F.SilkS")
			(effects
				(font
					(size 0.7 0.7)
					(thickness 0.15)
				)
				(justify left bottom)
			)
		)
		(property "Value" "R_470R_0402"
			(at 0 1.4 180)
			(layer "F.Fab")
			(effects
				(font
					(size 0.7 0.7)
					(thickness 0.15)
				)
				(justify left bottom)
			)
		)
		(property "Footprint" "antmicro-footprints:R_0402_1005Metric"
			(at 0 0 180)
			(layer "F.Fab")
			(hide yes)
			(effects
				(font
					(size 1.27 1.27)
					(thickness 0.15)
				)
			)
		)
		(property "Datasheet" "https://www.bourns.com/docs/product-datasheets/cr.pdf"
			(at 0 0 180)
			(layer "F.Fab")
			(hide yes)
			(effects
				(font
					(size 1.27 1.27)
					(thickness 0.15)
				)
			)
		)
		(property "Author" "Antmicro"
			(at 296 221 0)
			(layer "F.Fab")
			(hide yes)
			(effects
				(font
					(size 1 1)
					(thickness 0.15)
				)
			)
		)
		(property "License" "Apache-2.0"
			(at 296 221 0)
			(layer "F.Fab")
			(hide yes)
			(effects
				(font
					(size 1 1)
					(thickness 0.15)
				)
			)
		)
		(property "MPN" "CR0402-FX-4700GLF"
			(at 296 221 0)
			(layer "F.Fab")
			(hide yes)
			(effects
				(font
					(size 1 1)
					(thickness 0.15)
				)
			)
		)
		(property "Manufacturer" "Bourns"
			(at 296 221 0)
			(layer "F.Fab")
			(hide yes)
			(effects
				(font
					(size 1 1)
					(thickness 0.15)
				)
			)
		)
		(property "Tolerance" "1%"
			(at 296 221 0)
			(layer "F.Fab")
			(hide yes)
			(effects
				(font
					(size 1 1)
					(thickness 0.15)
				)
			)
		)
		(property "Val" "470R"
			(at 296 221 0)
			(layer "F.Fab")
			(hide yes)
			(effects
				(font
					(size 1 1)
					(thickness 0.15)
				)
			)
		)
		(sheetname "Peripherals")
		(sheetfile "peripherals.kicad_sch")
		(attr smd)
		(fp_rect
			(start -0.925 -0.47)
			(end 0.925 0.47)
			(stroke
				(width 0.05)
				(type default)
			)
			(fill none)
			(layer "F.CrtYd")
		)
		(fp_rect
			(start -0.5 -0.25)
			(end 0.5 0.25)
			(stroke
				(width 0.15)
				(type solid)
			)
			(fill none)
			(layer "F.Fab")
		)
		(fp_text user "Author: Antmicro"
			(at -0.95 4.169 180)
			(layer "F.Fab")
			(hide yes)
			(effects
				(font
					(size 0.7 0.7)
					(thickness 0.15)
				)
				(justify left bottom)
			)
		)
		(fp_text user "License: Apache-2.0"
			(at -0.95 5.169 180)
			(layer "F.Fab")
			(hide yes)
			(effects
				(font
					(size 0.7 0.7)
					(thickness 0.15)
				)
				(justify left bottom)
			)
		)
		(fp_text user "${REFERENCE}"
			(at -0.95 3.168 180)
			(layer "F.Fab")
			(hide yes)
			(effects
				(font
					(size 0.7 0.7)
					(thickness 0.15)
				)
				(justify left bottom)
			)
		)
		(pad "1" smd roundrect
			(at -0.48 0 180)
			(size 0.59 0.64)
			(layers "F.Cu" "F.Paste" "F.Mask")
			(roundrect_rratio 0.25)
			(net 100 "CAN_RX")
			(pintype "passive")
		)
		(pad "2" smd roundrect
			(at 0.48 0 180)
			(size 0.59 0.64)
			(layers "F.Cu" "F.Paste" "F.Mask")
			(roundrect_rratio 0.25)
			(net 600 "Net-(J11-Pad68)")
			(pintype "passive")
		)
	)
	(footprint "antmicro-footprints:C_0402_1005Metric"
		(layer "F.Cu")
		(at 81.9 104.6 180)
		(descr "Capacitor SMD 0402")
		(tags "capacitor SMD 0402")
		(property "Reference" "C144"
			(at -0.8 -0.45 180)
			(layer "F.SilkS")
			(effects
				(font
					(size 0.7 0.7)
					(thickness 0.15)
				)
				(justify left bottom)
			)
		)
		(property "Value" "C_100n_0402"
			(at 0 1.4 180)
			(layer "F.Fab")
			(effects
				(font
					(size 0.7 0.7)
					(thickness 0.15)
				)
				(justify left bottom)
			)
		)
		(property "Footprint" "antmicro-footprints:C_0402_1005Metric"
			(at 0 0 180)
			(layer "F.Fab")
			(hide yes)
			(effects
				(font
					(size 1.27 1.27)
					(thickness 0.15)
				)
			)
		)
		(property "Datasheet" "https://www.murata.com/products/productdetail?partno=GRM155R61H104KE14%23"
			(at 0 0 180)
			(layer "F.Fab")
			(hide yes)
			(effects
				(font
					(size 1.27 1.27)
					(thickness 0.15)
				)
			)
		)
		(property "Author" "Antmicro"
			(at 163.8 209.2 0)
			(layer "F.Fab")
			(hide yes)
			(effects
				(font
					(size 1 1)
					(thickness 0.15)
				)
			)
		)
		(property "Dielectric" "X5R"
			(at 163.8 209.2 0)
			(layer "F.Fab")
			(hide yes)
			(effects
				(font
					(size 1 1)
					(thickness 0.15)
				)
			)
		)
		(property "License" "Apache-2.0"
			(at 163.8 209.2 0)
			(layer "F.Fab")
			(hide yes)
			(effects
				(font
					(size 1 1)
					(thickness 0.15)
				)
			)
		)
		(property "MPN" "GRM155R61H104KE14D"
			(at 163.8 209.2 0)
			(layer "F.Fab")
			(hide yes)
			(effects
				(font
					(size 1 1)
					(thickness 0.15)
				)
			)
		)
		(property "Manufacturer" "Murata"
			(at 163.8 209.2 0)
			(layer "F.Fab")
			(hide yes)
			(effects
				(font
					(size 1 1)
					(thickness 0.15)
				)
			)
		)
		(property "Val" "100n"
			(at 163.8 209.2 0)
			(layer "F.Fab")
			(hide yes)
			(effects
				(font
					(size 1 1)
					(thickness 0.15)
				)
			)
		)
		(property "Voltage" "50V"
			(at 163.8 209.2 0)
			(layer "F.Fab")
			(hide yes)
			(effects
				(font
					(size 1 1)
					(thickness 0.15)
				)
			)
		)
		(sheetname "USB Debug, DP")
		(sheetfile "usb.kicad_sch")
		(attr smd)
		(fp_rect
			(start -0.925 -0.47)
			(end 0.925 0.47)
			(stroke
				(width 0.05)
				(type default)
			)
			(fill none)
			(layer "F.CrtYd")
		)
		(fp_line
			(start 0.504 0.248)
			(end -0.494 0.248)
			(stroke
				(width 0.15)
				(type solid)
			)
			(layer "F.Fab")
		)
		(fp_line
			(start 0.504 -0.25)
			(end 0.504 0.248)
			(stroke
				(width 0.15)
				(type solid)
			)
			(layer "F.Fab")
		)
		(fp_line
			(start -0.494 0.248)
			(end -0.494 -0.25)
			(stroke
				(width 0.15)
				(type solid)
			)
			(layer "F.Fab")
		)
		(fp_line
			(start -0.494 -0.25)
			(end 0.504 -0.25)
			(stroke
				(width 0.15)
				(type solid)
			)
			(layer "F.Fab")
		)
		(fp_text user "Author: Antmicro"
			(at -0.932 4.17 180)
			(layer "F.Fab")
			(hide yes)
			(effects
				(font
					(size 0.7 0.7)
					(thickness 0.15)
				)
				(justify left bottom)
			)
		)
		(fp_text user "License: Apache-2.0"
			(at -0.932 5.17 180)
			(layer "F.Fab")
			(hide yes)
			(effects
				(font
					(size 0.7 0.7)
					(thickness 0.15)
				)
				(justify left bottom)
			)
		)
		(fp_text user "${REFERENCE}"
			(at -0.932 3.168 180)
			(layer "F.Fab")
			(hide yes)
			(effects
				(font
					(size 0.7 0.7)
					(thickness 0.15)
				)
				(justify left bottom)
			)
		)
		(pad "1" smd roundrect
			(at -0.48 0 180)
			(size 0.59 0.64)
			(layers "F.Cu" "F.Paste" "F.Mask")
			(roundrect_rratio 0.25)
			(net 59 "USBSS0_TX_N")
			(pintype "passive")
		)
		(pad "2" smd roundrect
			(at 0.48 0 180)
			(size 0.59 0.64)
			(layers "F.Cu" "F.Paste" "F.Mask")
			(roundrect_rratio 0.25)
			(net 194 "/USB Debug, DP/USBSS0_TX_C_P")
			(pintype "passive")
		)
	)
)
